# S9S_MB_2U (Grand Teton) — schematic netlist excerpt (pin names and nets, part order shuffled) for the footprints in the layout excerpt that follows; sources: Cadence DE-HDL packaged netlist, KiCad conversion of 03242023_DA0F0TMBIJ0_F0T_Motherboard_J_brd_V01_OCP.brd

R3318  Q_RES  100K 1% EMPTY  pkg 0402LF  page 148 : A = P3V3_AUX ; B = GPU_FPGA_READY

U66  74LVC1G126SE7  74LVC1G126SE-7 IC  pkg SOT353_0-65_2X1-25  page 154
  OE  = OCP_SFF_AUX_PWR_EN_R1
  A  = FM_OCP_SFF_PWR_GOOD
  GND  = GND
  Y  = FB_BMC_ISOLATE_R1
  VCC  = P3V3_AUX

(kicad_pcb
	(version 20260206)
	(generator "pcbnew")
	(generator_version "10.0")
	(general
		(thickness 1.6)
		(legacy_teardrops no)
	)
	(paper "A4")
	(title_block
		(title "03242023_DA0F0TMBIJ0_F0T_Motherboard_J_brd_V01_OCP.brd")
		(comment 1 "Grand Teton / footprints 2512-2513 of 6105")
	)
	(layers
		(0 "F.Cu" signal "TOP")
		(4 "In1.Cu" signal "GND")
		(6 "In2.Cu" signal "IN1")
		(8 "In3.Cu" signal "GND1")
		(10 "In4.Cu" signal "IN2")
		(12 "In5.Cu" signal "GND2")
		(14 "In6.Cu" signal "IN3")
		(16 "In7.Cu" signal "GND3")
		(18 "In8.Cu" signal "VCC")
		(20 "In9.Cu" signal "VCC1")
		(22 "In10.Cu" signal "GND4")
		(24 "In11.Cu" signal "IN4")
		(26 "In12.Cu" signal "GND5")
		(28 "In13.Cu" signal "IN5")
		(30 "In14.Cu" signal "GND6")
		(32 "In15.Cu" signal "IN6")
		(34 "In16.Cu" signal "GND7")
		(2 "B.Cu" signal "BOTTOM")
		(9 "F.Adhes" user "F.Adhesive")
		(11 "B.Adhes" user "B.Adhesive")
		(13 "F.Paste" user "Package Geometry/Pastemask Top")
		(15 "B.Paste" user "Package Geometry/Pastemask Bottom")
		(5 "F.SilkS" user "Ref Des/Silkscreen Top")
		(7 "B.SilkS" user "Ref Des/Silkscreen Bottom")
		(1 "F.Mask" user "Board Geometry/Soldermask Top")
		(3 "B.Mask" user "Board Geometry/Soldermask Bottom")
		(17 "Dwgs.User" user "User.Drawings")
		(19 "Cmts.User" user "User.Comments")
		(21 "Eco1.User" user "User.Eco1")
		(23 "Eco2.User" user "User.Eco2")
		(25 "Edge.Cuts" user "Board Geometry/Outline")
		(27 "Margin" user)
		(31 "F.CrtYd" user "Package Geometry/Place Bound Top")
		(29 "B.CrtYd" user "Package Geometry/Place Bound Bottom")
		(35 "F.Fab" user "Ref Des/Assembly Top")
		(33 "B.Fab" user "Ref Des/Assembly Bottom")
	)
	(footprint ""
		(layer "F.Cu")
		(at 459.579726 -98.514408)
		(property "Reference" "U66"
			(at -3.89636 -2.009648 0)
			(unlocked yes)
			(layer "F.SilkS")
			(effects
				(font
					(size 0.7874 0.5842)
					(thickness 0.1524)
				)
				(justify left)
			)
		)
		(property "Value" ""
			(at 0 0 0)
			(layer "F.Fab")
			(effects
				(font
					(size 1.27 1.27)
				)
			)
		)
		(duplicate_pad_numbers_are_jumpers no)
		(fp_line
			(start -1.400048 1.100074)
			(end -1.400048 -1.100074)
			(stroke
				(width 0.1524)
				(type default)
			)
			(layer "F.SilkS")
		)
		(fp_line
			(start 1.400048 -1.100074)
			(end -1.400048 -1.100074)
			(stroke
				(width 0.1524)
				(type default)
			)
			(layer "F.SilkS")
		)
		(fp_line
			(start 1.400048 -1.100074)
			(end 1.400048 1.100074)
			(stroke
				(width 0.1524)
				(type default)
			)
			(layer "F.SilkS")
		)
		(fp_line
			(start 1.400048 1.100074)
			(end -1.400048 1.100074)
			(stroke
				(width 0.1524)
				(type default)
			)
			(layer "F.SilkS")
		)
		(fp_poly
			(pts
				(xy -1.03886 -1.265682) (xy -1.54686 -2.281682) (xy -0.53086 -2.281682)
			)
			(stroke
				(width 0)
				(type default)
			)
			(fill yes)
			(layer "F.SilkS")
		)
		(fp_line
			(start -0.674878 -1.100074)
			(end 0.674878 -1.100074)
			(stroke
				(width 0.1)
				(type default)
			)
			(layer "F.Fab")
		)
		(fp_line
			(start -0.674878 1.100074)
			(end -0.674878 -1.100074)
			(stroke
				(width 0.1)
				(type default)
			)
			(layer "F.Fab")
		)
		(fp_line
			(start 0.674878 -1.100074)
			(end 0.674878 1.100074)
			(stroke
				(width 0.1)
				(type default)
			)
			(layer "F.Fab")
		)
		(fp_line
			(start 0.674878 1.100074)
			(end -0.674878 1.100074)
			(stroke
				(width 0.1)
				(type default)
			)
			(layer "F.Fab")
		)
		(fp_poly
			(pts
				(xy -1.590548 -0.649986) (xy -2.606548 -1.157986) (xy -2.606548 -0.141986)
			)
			(stroke
				(width 0)
				(type default)
			)
			(fill yes)
			(layer "F.Fab")
		)
		(pad "1" smd rect
			(at -0.94996 -0.649986 270)
			(size 0.4318 0.6096)
			(layers "F.Cu" "F.Mask" "F.Paste")
			(net "OCP_SFF_AUX_PWR_EN_R1")
		)
		(pad "2" smd rect
			(at -0.94996 0 270)
			(size 0.4318 0.6096)
			(layers "F.Cu" "F.Mask" "F.Paste")
			(net "FM_OCP_SFF_PWR_GOOD")
		)
		(pad "3" smd rect
			(at -0.94996 0.649986 270)
			(size 0.4318 0.6096)
			(layers "F.Cu" "F.Mask" "F.Paste")
			(net "GND")
		)
		(pad "4" smd rect
			(at 0.94996 0.649986 270)
			(size 0.4318 0.6096)
			(layers "F.Cu" "F.Mask" "F.Paste")
			(net "FB_BMC_ISOLATE_R1")
		)
		(pad "5" smd rect
			(at 0.94996 -0.649986 270)
			(size 0.4318 0.6096)
			(layers "F.Cu" "F.Mask" "F.Paste")
			(net "P3V3_AUX")
		)
	)
	(footprint ""
		(layer "F.Cu")
		(at 21.752052 -403.827488)
		(property "Reference" "R3318"
			(at 0 0 0)
			(layer "F.SilkS")
			(hide yes)
			(effects
				(font
					(size 1.27 1.27)
				)
			)
		)
		(property "Value" ""
			(at 0 0 0)
			(layer "F.Fab")
			(effects
				(font
					(size 1.27 1.27)
				)
			)
		)
		(duplicate_pad_numbers_are_jumpers no)
		(fp_line
			(start -0.7874 -0.4064)
			(end 0.7874 -0.4064)
			(stroke
				(width 0.1524)
				(type default)
			)
			(layer "F.SilkS")
		)
		(fp_line
			(start -0.7874 0.4064)
			(end -0.7874 -0.4064)
			(stroke
				(width 0.1524)
				(type default)
			)
			(layer "F.SilkS")
		)
		(fp_line
			(start 0.7874 -0.4064)
			(end 0.7874 0.4064)
			(stroke
				(width 0.1524)
				(type default)
			)
			(layer "F.SilkS")
		)
		(fp_line
			(start 0.7874 0.4064)
			(end -0.7874 0.4064)
			(stroke
				(width 0.1524)
				(type default)
			)
			(layer "F.SilkS")
		)
		(fp_line
			(start -0.67945 -0.305054)
			(end -0.12065 -0.305054)
			(stroke
				(width 0.1)
				(type default)
			)
			(layer "F.Fab")
		)
		(fp_line
			(start -0.67945 0.3048)
			(end -0.67945 -0.305054)
			(stroke
				(width 0.1)
				(type default)
			)
			(layer "F.Fab")
		)
		(fp_line
			(start -0.12065 -0.305054)
			(end -0.12065 -0.2794)
			(stroke
				(width 0.1)
				(type default)
			)
			(layer "F.Fab")
		)
		(fp_line
			(start -0.12065 -0.2794)
			(end 0.12065 -0.2794)
			(stroke
				(width 0.1)
				(type default)
			)
			(layer "F.Fab")
		)
		(fp_line
			(start -0.12065 0.2794)
			(end -0.12065 0.3048)
			(stroke
				(width 0.1)
				(type default)
			)
			(layer "F.Fab")
		)
		(fp_line
			(start -0.12065 0.3048)
			(end -0.67945 0.3048)
			(stroke
				(width 0.1)
				(type default)
			)
			(layer "F.Fab")
		)
		(fp_line
			(start 0.120396 0.2794)
			(end -0.12065 0.2794)
			(stroke
				(width 0.1)
				(type default)
			)
			(layer "F.Fab")
		)
		(fp_line
			(start 0.120396 0.3048)
			(end 0.120396 0.2794)
			(stroke
				(width 0.1)
				(type default)
			)
			(layer "F.Fab")
		)
		(fp_line
			(start 0.12065 -0.3048)
			(end 0.67945 -0.3048)
			(stroke
				(width 0.1)
				(type default)
			)
			(layer "F.Fab")
		)
		(fp_line
			(start 0.12065 -0.2794)
			(end 0.12065 -0.3048)
			(stroke
				(width 0.1)
				(type default)
			)
			(layer "F.Fab")
		)
		(fp_line
			(start 0.67945 -0.3048)
			(end 0.67945 0.3048)
			(stroke
				(width 0.1)
				(type default)
			)
			(layer "F.Fab")
		)
		(fp_line
			(start 0.67945 0.3048)
			(end 0.120396 0.3048)
			(stroke
				(width 0.1)
				(type default)
			)
			(layer "F.Fab")
		)
		(pad "1" smd circle
			(at -0.40005 0)
			(size 0 0)
			(layers "F.Cu" "F.Mask" "F.Paste")
			(net "P3V3_AUX")
		)
		(pad "2" smd circle
			(at 0.40005 0)
			(size 0 0)
			(layers "F.Cu" "F.Mask" "F.Paste")
			(net "GPU_FPGA_READY")
		)
	)
)
